# T6G (Grand Teton) — schematic netlist excerpt (pin names and nets, part order shuffled) for the footprints in the layout excerpt that follows; sources: Cadence DE-HDL packaged netlist, KiCad conversion of 04192023_DAF0TMB3IC0_F0TG_MB_C_brd_V02_OCP.brd

R1530  Q_RES  1K 1% EMPTY  pkg 0402LF  page 77 : A = PVDD18_S5_P0 ; B = SPI_CPU0_D2
PC89  Q_CAPP  390UF 2.5V 20% ALUM  pkg SMLF  page 226 : A = PVDD18_S5_P1 ; B = GND

(kicad_pcb
	(version 20260206)
	(generator "pcbnew")
	(generator_version "10.0")
	(general
		(thickness 1.6)
		(legacy_teardrops no)
	)
	(paper "A4")
	(title_block
		(title "04192023_DAF0TMB3IC0_F0TG_MB_C_brd_V02_OCP.brd")
		(comment 1 "Grand Teton / footprints 2935-2936 of 8354")
	)
	(layers
		(0 "F.Cu" signal "TOP")
		(4 "In1.Cu" signal "GND")
		(6 "In2.Cu" signal "IN1")
		(8 "In3.Cu" signal "GND1")
		(10 "In4.Cu" signal "IN2")
		(12 "In5.Cu" signal "GND2")
		(14 "In6.Cu" signal "IN3")
		(16 "In7.Cu" signal "GND3")
		(18 "In8.Cu" signal "VCC")
		(20 "In9.Cu" signal "VCC1")
		(22 "In10.Cu" signal "GND4")
		(24 "In11.Cu" signal "IN4")
		(26 "In12.Cu" signal "GND5")
		(28 "In13.Cu" signal "IN5")
		(30 "In14.Cu" signal "GND6")
		(32 "In15.Cu" signal "IN6")
		(34 "In16.Cu" signal "GND7")
		(2 "B.Cu" signal "BOTTOM")
		(9 "F.Adhes" user "F.Adhesive")
		(11 "B.Adhes" user "B.Adhesive")
		(13 "F.Paste" user "Package Geometry/Pastemask Top")
		(15 "B.Paste" user "Package Geometry/Pastemask Bottom")
		(5 "F.SilkS" user "Ref Des/Silkscreen Top")
		(7 "B.SilkS" user "Ref Des/Silkscreen Bottom")
		(1 "F.Mask" user "Board Geometry/Soldermask Top")
		(3 "B.Mask" user "Board Geometry/Soldermask Bottom")
		(17 "Dwgs.User" user "User.Drawings")
		(19 "Cmts.User" user "User.Comments")
		(21 "Eco1.User" user "User.Eco1")
		(23 "Eco2.User" user "User.Eco2")
		(25 "Edge.Cuts" user "Board Geometry/Outline")
		(27 "Margin" user)
		(31 "F.CrtYd" user "Package Geometry/Place Bound Top")
		(29 "B.CrtYd" user "Package Geometry/Place Bound Bottom")
		(35 "F.Fab" user "Ref Des/Assembly Top")
		(33 "B.Fab" user "Ref Des/Assembly Bottom")
	)
	(footprint ""
		(layer "F.Cu")
		(at 54.010814 -159.399478 180)
		(property "Reference" "PC89"
			(at 2.781808 3.588512 0)
			(unlocked yes)
			(layer "F.SilkS")
			(effects
				(font
					(size 0.7874 0.5842)
					(thickness 0.1524)
				)
				(justify left)
			)
		)
		(property "Value" ""
			(at 0 0 180)
			(layer "F.Fab")
			(effects
				(font
					(size 1.27 1.27)
				)
			)
		)
		(duplicate_pad_numbers_are_jumpers no)
		(fp_line
			(start 2.750058 2.750058)
			(end 2.750058 0.9398)
			(stroke
				(width 0.1524)
				(type default)
			)
			(layer "F.SilkS")
		)
		(fp_line
			(start 2.750058 -0.9398)
			(end 2.750058 -2.750058)
			(stroke
				(width 0.1524)
				(type default)
			)
			(layer "F.SilkS")
		)
		(fp_line
			(start 2.750058 -2.750058)
			(end -1.988058 -2.750058)
			(stroke
				(width 0.1524)
				(type default)
			)
			(layer "F.SilkS")
		)
		(fp_line
			(start -1.988058 2.750058)
			(end 2.750058 2.750058)
			(stroke
				(width 0.1524)
				(type default)
			)
			(layer "F.SilkS")
		)
		(fp_line
			(start -1.988058 -2.750058)
			(end -2.750058 -1.988058)
			(stroke
				(width 0.1524)
				(type default)
			)
			(layer "F.SilkS")
		)
		(fp_line
			(start -2.750058 1.988058)
			(end -1.988058 2.750058)
			(stroke
				(width 0.1524)
				(type default)
			)
			(layer "F.SilkS")
		)
		(fp_line
			(start -2.750058 0.9398)
			(end -2.750058 1.988058)
			(stroke
				(width 0.1524)
				(type default)
			)
			(layer "F.SilkS")
		)
		(fp_line
			(start -2.750058 -1.988058)
			(end -2.750058 -0.9398)
			(stroke
				(width 0.1524)
				(type default)
			)
			(layer "F.SilkS")
		)
		(fp_line
			(start 2.750058 2.750058)
			(end 2.750058 -2.750058)
			(stroke
				(width 0.1)
				(type default)
			)
			(layer "F.Fab")
		)
		(fp_line
			(start 2.750058 -2.750058)
			(end -2.750058 -2.750058)
			(stroke
				(width 0.1)
				(type default)
			)
			(layer "F.Fab")
		)
		(fp_line
			(start -2.750058 2.750058)
			(end 2.750058 2.750058)
			(stroke
				(width 0.1)
				(type default)
			)
			(layer "F.Fab")
		)
		(fp_line
			(start -2.750058 -2.750058)
			(end -2.750058 2.750058)
			(stroke
				(width 0.1)
				(type default)
			)
			(layer "F.Fab")
		)
		(pad "1" smd rect
			(at -2.199894 0 270)
			(size 1.6002 3.0226)
			(layers "F.Cu" "F.Mask" "F.Paste")
			(net "PVDD18_S5_P1")
		)
		(pad "2" smd rect
			(at 2.199894 0 270)
			(size 1.6002 3.0226)
			(layers "F.Cu" "F.Mask" "F.Paste")
			(net "GND")
		)
	)
	(footprint ""
		(layer "F.Cu")
		(at 264.986516 -139.591796 180)
		(property "Reference" "R1530"
			(at 0 0 180)
			(layer "F.SilkS")
			(hide yes)
			(effects
				(font
					(size 1.27 1.27)
				)
			)
		)
		(property "Value" ""
			(at 0 0 180)
			(layer "F.Fab")
			(effects
				(font
					(size 1.27 1.27)
				)
			)
		)
		(duplicate_pad_numbers_are_jumpers no)
		(fp_line
			(start 0.7874 0.4064)
			(end -0.7874 0.4064)
			(stroke
				(width 0.1524)
				(type default)
			)
			(layer "F.SilkS")
		)
		(fp_line
			(start 0.7874 -0.4064)
			(end 0.7874 0.4064)
			(stroke
				(width 0.1524)
				(type default)
			)
			(layer "F.SilkS")
		)
		(fp_line
			(start -0.7874 0.4064)
			(end -0.7874 -0.4064)
			(stroke
				(width 0.1524)
				(type default)
			)
			(layer "F.SilkS")
		)
		(fp_line
			(start -0.7874 -0.4064)
			(end 0.7874 -0.4064)
			(stroke
				(width 0.1524)
				(type default)
			)
			(layer "F.SilkS")
		)
		(fp_line
			(start 0.67945 0.3048)
			(end 0.120396 0.3048)
			(stroke
				(width 0.1)
				(type default)
			)
			(layer "F.Fab")
		)
		(fp_line
			(start 0.67945 -0.3048)
			(end 0.67945 0.3048)
			(stroke
				(width 0.1)
				(type default)
			)
			(layer "F.Fab")
		)
		(fp_line
			(start 0.12065 -0.2794)
			(end 0.12065 -0.3048)
			(stroke
				(width 0.1)
				(type default)
			)
			(layer "F.Fab")
		)
		(fp_line
			(start 0.12065 -0.3048)
			(end 0.67945 -0.3048)
			(stroke
				(width 0.1)
				(type default)
			)
			(layer "F.Fab")
		)
		(fp_line
			(start 0.120396 0.3048)
			(end 0.120396 0.2794)
			(stroke
				(width 0.1)
				(type default)
			)
			(layer "F.Fab")
		)
		(fp_line
			(start 0.120396 0.2794)
			(end -0.12065 0.2794)
			(stroke
				(width 0.1)
				(type default)
			)
			(layer "F.Fab")
		)
		(fp_line
			(start -0.12065 0.3048)
			(end -0.67945 0.3048)
			(stroke
				(width 0.1)
				(type default)
			)
			(layer "F.Fab")
		)
		(fp_line
			(start -0.12065 0.2794)
			(end -0.12065 0.3048)
			(stroke
				(width 0.1)
				(type default)
			)
			(layer "F.Fab")
		)
		(fp_line
			(start -0.12065 -0.2794)
			(end 0.12065 -0.2794)
			(stroke
				(width 0.1)
				(type default)
			)
			(layer "F.Fab")
		)
		(fp_line
			(start -0.12065 -0.305054)
			(end -0.12065 -0.2794)
			(stroke
				(width 0.1)
				(type default)
			)
			(layer "F.Fab")
		)
		(fp_line
			(start -0.67945 0.3048)
			(end -0.67945 -0.305054)
			(stroke
				(width 0.1)
				(type default)
			)
			(layer "F.Fab")
		)
		(fp_line
			(start -0.67945 -0.305054)
			(end -0.12065 -0.305054)
			(stroke
				(width 0.1)
				(type default)
			)
			(layer "F.Fab")
		)
		(pad "1" smd circle
			(at -0.40005 0 180)
			(size 0 0)
			(layers "F.Cu" "F.Mask" "F.Paste")
			(net "PVDD18_S5_P0")
		)
		(pad "2" smd circle
			(at 0.40005 0 180)
			(size 0 0)
			(layers "F.Cu" "F.Mask" "F.Paste")
			(net "SPI_CPU0_D2")
		)
	)
)
